(kicad_pcb
	(version 20260206)
	(generator "pcbnew")
	(generator_version "10.0")
	(general
		(thickness 1.6)
		(legacy_teardrops no)
	)
	(paper "A4")
	(title_block
		(title "03242023_DA0F0TMBIJ0_F0T_Motherboard_J_brd_V01_OCP.brd")
		(comment 1 "Grand Teton / footprint 663 of 6105 (J21), pads 113-224 of 291")
	)
	(layers
		(0 "F.Cu" signal "TOP")
		(4 "In1.Cu" signal "GND")
		(6 "In2.Cu" signal "IN1")
		(8 "In3.Cu" signal "GND1")
		(10 "In4.Cu" signal "IN2")
		(12 "In5.Cu" signal "GND2")
		(14 "In6.Cu" signal "IN3")
		(16 "In7.Cu" signal "GND3")
		(18 "In8.Cu" signal "VCC")
		(20 "In9.Cu" signal "VCC1")
		(22 "In10.Cu" signal "GND4")
		(24 "In11.Cu" signal "IN4")
		(26 "In12.Cu" signal "GND5")
		(28 "In13.Cu" signal "IN5")
		(30 "In14.Cu" signal "GND6")
		(32 "In15.Cu" signal "IN6")
		(34 "In16.Cu" signal "GND7")
		(2 "B.Cu" signal "BOTTOM")
		(9 "F.Adhes" user "F.Adhesive")
		(11 "B.Adhes" user "B.Adhesive")
		(13 "F.Paste" user "Package Geometry/Pastemask Top")
		(15 "B.Paste" user "Package Geometry/Pastemask Bottom")
		(5 "F.SilkS" user "Ref Des/Silkscreen Top")
		(7 "B.SilkS" user "Ref Des/Silkscreen Bottom")
		(1 "F.Mask" user "Board Geometry/Soldermask Top")
		(3 "B.Mask" user "Board Geometry/Soldermask Bottom")
		(17 "Dwgs.User" user "User.Drawings")
		(19 "Cmts.User" user "User.Comments")
		(21 "Eco1.User" user "User.Eco1")
		(23 "Eco2.User" user "User.Eco2")
		(25 "Edge.Cuts" user "Board Geometry/Outline")
		(27 "Margin" user)
		(31 "F.CrtYd" user "Package Geometry/Place Bound Top")
		(29 "B.CrtYd" user "Package Geometry/Place Bound Bottom")
		(35 "F.Fab" user "Ref Des/Assembly Top")
		(33 "B.Fab" user "Ref Des/Assembly Bottom")
	)
	(footprint ""
		(layer "F.Cu")
		(at 25.27808 -258.091686)
		(property "Reference" "J21"
			(at -0.325882 -81.821274 0)
			(unlocked yes)
			(layer "F.SilkS")
			(effects
				(font
					(size 0.7874 0.5842)
					(thickness 0.1524)
				)
				(justify left)
			)
		)
		(property "Value" ""
			(at 0 0 0)
			(layer "F.Fab")
			(effects
				(font
					(size 1.27 1.27)
				)
			)
		)
		(duplicate_pad_numbers_are_jumpers no)
		(pad "113" smd rect
			(at -2.050034 36.975034 270)
			(size 0.519938 1.4986)
			(layers "F.Cu" "F.Mask" "F.Paste")
			(net "M_C_CPU1_SB_DQ<9>")
		)
		(pad "114" smd rect
			(at -2.050034 37.824918 270)
			(size 0.519938 1.4986)
			(layers "F.Cu" "F.Mask" "F.Paste")
			(net "GND")
		)
		(pad "115" smd rect
			(at -2.050034 38.675056 270)
			(size 0.519938 1.4986)
			(layers "F.Cu" "F.Mask" "F.Paste")
			(net "M_C_CPU1_SB_DQS_DP<1>")
		)
		(pad "116" smd rect
			(at -2.050034 39.52494 270)
			(size 0.519938 1.4986)
			(layers "F.Cu" "F.Mask" "F.Paste")
			(net "M_C_CPU1_SB_DQS_DN<1>")
		)
		(pad "117" smd rect
			(at -2.050034 40.375078 270)
			(size 0.519938 1.4986)
			(layers "F.Cu" "F.Mask" "F.Paste")
			(net "GND")
		)
		(pad "118" smd rect
			(at -2.050034 41.224962 270)
			(size 0.519938 1.4986)
			(layers "F.Cu" "F.Mask" "F.Paste")
			(net "M_C_CPU1_SB_DQ<12>")
		)
		(pad "119" smd rect
			(at -2.050034 42.0751 270)
			(size 0.519938 1.4986)
			(layers "F.Cu" "F.Mask" "F.Paste")
			(net "GND")
		)
		(pad "120" smd rect
			(at -2.050034 42.924984 270)
			(size 0.519938 1.4986)
			(layers "F.Cu" "F.Mask" "F.Paste")
			(net "M_C_CPU1_SB_DQ<13>")
		)
		(pad "121" smd rect
			(at -2.050034 43.775122 270)
			(size 0.519938 1.4986)
			(layers "F.Cu" "F.Mask" "F.Paste")
			(net "GND")
		)
		(pad "122" smd rect
			(at -2.050034 44.625006 270)
			(size 0.519938 1.4986)
			(layers "F.Cu" "F.Mask" "F.Paste")
			(net "M_C_CPU1_SB_DQ<16>")
		)
		(pad "123" smd rect
			(at -2.050034 45.47489 270)
			(size 0.519938 1.4986)
			(layers "F.Cu" "F.Mask" "F.Paste")
			(net "GND")
		)
		(pad "124" smd rect
			(at -2.050034 46.325028 270)
			(size 0.519938 1.4986)
			(layers "F.Cu" "F.Mask" "F.Paste")
			(net "M_C_CPU1_SB_DQ<17>")
		)
		(pad "125" smd rect
			(at -2.050034 47.174912 270)
			(size 0.519938 1.4986)
			(layers "F.Cu" "F.Mask" "F.Paste")
			(net "GND")
		)
		(pad "126" smd rect
			(at -2.050034 48.02505 270)
			(size 0.519938 1.4986)
			(layers "F.Cu" "F.Mask" "F.Paste")
			(net "M_C_CPU1_SB_DQS_DP<2>")
		)
		(pad "127" smd rect
			(at -2.050034 48.874934 270)
			(size 0.519938 1.4986)
			(layers "F.Cu" "F.Mask" "F.Paste")
			(net "M_C_CPU1_SB_DQS_DN<2>")
		)
		(pad "128" smd rect
			(at -2.050034 49.725072 270)
			(size 0.519938 1.4986)
			(layers "F.Cu" "F.Mask" "F.Paste")
			(net "GND")
		)
		(pad "129" smd rect
			(at -2.050034 50.574956 270)
			(size 0.519938 1.4986)
			(layers "F.Cu" "F.Mask" "F.Paste")
			(net "M_C_CPU1_SB_DQ<20>")
		)
		(pad "130" smd rect
			(at -2.050034 51.425094 270)
			(size 0.519938 1.4986)
			(layers "F.Cu" "F.Mask" "F.Paste")
			(net "GND")
		)
		(pad "131" smd rect
			(at -2.050034 52.274978 270)
			(size 0.519938 1.4986)
			(layers "F.Cu" "F.Mask" "F.Paste")
			(net "M_C_CPU1_SB_DQ<21>")
		)
		(pad "132" smd rect
			(at -2.050034 53.125116 270)
			(size 0.519938 1.4986)
			(layers "F.Cu" "F.Mask" "F.Paste")
			(net "GND")
		)
		(pad "133" smd rect
			(at -2.050034 53.975 270)
			(size 0.519938 1.4986)
			(layers "F.Cu" "F.Mask" "F.Paste")
			(net "M_C_CPU1_SB_DQ<24>")
		)
		(pad "134" smd rect
			(at -2.050034 54.824884 270)
			(size 0.519938 1.4986)
			(layers "F.Cu" "F.Mask" "F.Paste")
			(net "GND")
		)
		(pad "135" smd rect
			(at -2.050034 55.675022 270)
			(size 0.519938 1.4986)
			(layers "F.Cu" "F.Mask" "F.Paste")
			(net "M_C_CPU1_SB_DQ<25>")
		)
		(pad "136" smd rect
			(at -2.050034 56.524906 270)
			(size 0.519938 1.4986)
			(layers "F.Cu" "F.Mask" "F.Paste")
			(net "GND")
		)
		(pad "137" smd rect
			(at -2.050034 57.375044 270)
			(size 0.519938 1.4986)
			(layers "F.Cu" "F.Mask" "F.Paste")
			(net "M_C_CPU1_SB_DQS_DP<3>")
		)
		(pad "138" smd rect
			(at -2.050034 58.224928 270)
			(size 0.519938 1.4986)
			(layers "F.Cu" "F.Mask" "F.Paste")
			(net "M_C_CPU1_SB_DQS_DN<3>")
		)
		(pad "139" smd rect
			(at -2.050034 59.075066 270)
			(size 0.519938 1.4986)
			(layers "F.Cu" "F.Mask" "F.Paste")
			(net "GND")
		)
		(pad "140" smd rect
			(at -2.050034 59.92495 270)
			(size 0.519938 1.4986)
			(layers "F.Cu" "F.Mask" "F.Paste")
			(net "M_C_CPU1_SB_DQ<28>")
		)
		(pad "141" smd rect
			(at -2.050034 60.775088 270)
			(size 0.519938 1.4986)
			(layers "F.Cu" "F.Mask" "F.Paste")
			(net "GND")
		)
		(pad "142" smd rect
			(at -2.050034 61.624972 270)
			(size 0.519938 1.4986)
			(layers "F.Cu" "F.Mask" "F.Paste")
			(net "M_C_CPU1_SB_DQ<29>")
		)
		(pad "143" smd rect
			(at -2.050034 62.47511 270)
			(size 0.519938 1.4986)
			(layers "F.Cu" "F.Mask" "F.Paste")
			(net "GND")
		)
		(pad "144" smd rect
			(at -2.050034 63.324994 270)
			(size 0.519938 1.4986)
			(layers "F.Cu" "F.Mask" "F.Paste")
			(net "TP_CHC_CPU1_DIMM1_FRU_1")
		)
		(pad "145" smd rect
			(at 2.050034 -63.324994 270)
			(size 0.519938 1.4986)
			(layers "F.Cu" "F.Mask" "F.Paste")
			(net "P12V_S3_AUX_CPU1_NVDIMM")
		)
		(pad "146" smd rect
			(at 2.050034 -62.47511 270)
			(size 0.519938 1.4986)
			(layers "F.Cu" "F.Mask" "F.Paste")
			(net "P12V_S3_AUX_CPU1_NVDIMM")
		)
		(pad "147" smd rect
			(at 2.050034 -61.624972 270)
			(size 0.519938 1.4986)
			(layers "F.Cu" "F.Mask" "F.Paste")
			(net "PWRGD_CHC_CPU1_DIMM1")
		)
		(pad "148" smd rect
			(at 2.050034 -60.775088 270)
			(size 0.519938 1.4986)
			(layers "F.Cu" "F.Mask" "F.Paste")
			(net "PD_CHC_CPU1_DIMM1_SAA")
		)
		(pad "149" smd rect
			(at 2.050034 -59.92495 270)
			(size 0.519938 1.4986)
			(layers "F.Cu" "F.Mask" "F.Paste")
			(net "TP_CHC_CPU1_DIMM1_FRU_2")
		)
		(pad "150" smd rect
			(at 2.050034 -59.075066 270)
			(size 0.519938 1.4986)
			(layers "F.Cu" "F.Mask" "F.Paste")
			(net "TP_CHC_CPU1_DIMM1_FRU_3")
		)
		(pad "151" smd rect
			(at 2.050034 -58.224928 270)
			(size 0.519938 1.4986)
			(layers "F.Cu" "F.Mask" "F.Paste")
			(net "GND")
		)
		(pad "152" smd rect
			(at 2.050034 -57.375044 270)
			(size 0.519938 1.4986)
			(layers "F.Cu" "F.Mask" "F.Paste")
			(net "M_C_CPU1_SA_DQ<2>")
		)
		(pad "153" smd rect
			(at 2.050034 -56.524906 270)
			(size 0.519938 1.4986)
			(layers "F.Cu" "F.Mask" "F.Paste")
			(net "GND")
		)
		(pad "154" smd rect
			(at 2.050034 -55.675022 270)
			(size 0.519938 1.4986)
			(layers "F.Cu" "F.Mask" "F.Paste")
			(net "M_C_CPU1_SA_DQ<3>")
		)
		(pad "155" smd rect
			(at 2.050034 -54.824884 270)
			(size 0.519938 1.4986)
			(layers "F.Cu" "F.Mask" "F.Paste")
			(net "GND")
		)
		(pad "156" smd rect
			(at 2.050034 -53.975 270)
			(size 0.519938 1.4986)
			(layers "F.Cu" "F.Mask" "F.Paste")
			(net "M_C_CPU1_SA_DQS_DN<5>")
		)
		(pad "157" smd rect
			(at 2.050034 -53.125116 270)
			(size 0.519938 1.4986)
			(layers "F.Cu" "F.Mask" "F.Paste")
			(net "M_C_CPU1_SA_DQS_DP<5>")
		)
		(pad "158" smd rect
			(at 2.050034 -52.274978 270)
			(size 0.519938 1.4986)
			(layers "F.Cu" "F.Mask" "F.Paste")
			(net "GND")
		)
		(pad "159" smd rect
			(at 2.050034 -51.425094 270)
			(size 0.519938 1.4986)
			(layers "F.Cu" "F.Mask" "F.Paste")
			(net "M_C_CPU1_SA_DQ<6>")
		)
		(pad "160" smd rect
			(at 2.050034 -50.574956 270)
			(size 0.519938 1.4986)
			(layers "F.Cu" "F.Mask" "F.Paste")
			(net "GND")
		)
		(pad "161" smd rect
			(at 2.050034 -49.725072 270)
			(size 0.519938 1.4986)
			(layers "F.Cu" "F.Mask" "F.Paste")
			(net "M_C_CPU1_SA_DQ<7>")
		)
		(pad "162" smd rect
			(at 2.050034 -48.874934 270)
			(size 0.519938 1.4986)
			(layers "F.Cu" "F.Mask" "F.Paste")
			(net "GND")
		)
		(pad "163" smd rect
			(at 2.050034 -48.02505 270)
			(size 0.519938 1.4986)
			(layers "F.Cu" "F.Mask" "F.Paste")
			(net "M_C_CPU1_SA_DQ<10>")
		)
		(pad "164" smd rect
			(at 2.050034 -47.174912 270)
			(size 0.519938 1.4986)
			(layers "F.Cu" "F.Mask" "F.Paste")
			(net "GND")
		)
		(pad "165" smd rect
			(at 2.050034 -46.325028 270)
			(size 0.519938 1.4986)
			(layers "F.Cu" "F.Mask" "F.Paste")
			(net "M_C_CPU1_SA_DQ<11>")
		)
		(pad "166" smd rect
			(at 2.050034 -45.47489 270)
			(size 0.519938 1.4986)
			(layers "F.Cu" "F.Mask" "F.Paste")
			(net "GND")
		)
		(pad "167" smd rect
			(at 2.050034 -44.625006 270)
			(size 0.519938 1.4986)
			(layers "F.Cu" "F.Mask" "F.Paste")
			(net "M_C_CPU1_SA_DQS_DN<6>")
		)
		(pad "168" smd rect
			(at 2.050034 -43.775122 270)
			(size 0.519938 1.4986)
			(layers "F.Cu" "F.Mask" "F.Paste")
			(net "M_C_CPU1_SA_DQS_DP<6>")
		)
		(pad "169" smd rect
			(at 2.050034 -42.924984 270)
			(size 0.519938 1.4986)
			(layers "F.Cu" "F.Mask" "F.Paste")
			(net "GND")
		)
		(pad "170" smd rect
			(at 2.050034 -42.0751 270)
			(size 0.519938 1.4986)
			(layers "F.Cu" "F.Mask" "F.Paste")
			(net "M_C_CPU1_SA_DQ<14>")
		)
		(pad "171" smd rect
			(at 2.050034 -41.224962 270)
			(size 0.519938 1.4986)
			(layers "F.Cu" "F.Mask" "F.Paste")
			(net "GND")
		)
		(pad "172" smd rect
			(at 2.050034 -40.375078 270)
			(size 0.519938 1.4986)
			(layers "F.Cu" "F.Mask" "F.Paste")
			(net "M_C_CPU1_SA_DQ<15>")
		)
		(pad "173" smd rect
			(at 2.050034 -39.52494 270)
			(size 0.519938 1.4986)
			(layers "F.Cu" "F.Mask" "F.Paste")
			(net "GND")
		)
		(pad "174" smd rect
			(at 2.050034 -38.675056 270)
			(size 0.519938 1.4986)
			(layers "F.Cu" "F.Mask" "F.Paste")
			(net "M_C_CPU1_SA_DQ<18>")
		)
		(pad "175" smd rect
			(at 2.050034 -37.824918 270)
			(size 0.519938 1.4986)
			(layers "F.Cu" "F.Mask" "F.Paste")
			(net "GND")
		)
		(pad "176" smd rect
			(at 2.050034 -36.975034 270)
			(size 0.519938 1.4986)
			(layers "F.Cu" "F.Mask" "F.Paste")
			(net "M_C_CPU1_SA_DQ<19>")
		)
		(pad "177" smd rect
			(at 2.050034 -36.124896 270)
			(size 0.519938 1.4986)
			(layers "F.Cu" "F.Mask" "F.Paste")
			(net "GND")
		)
		(pad "178" smd rect
			(at 2.050034 -35.275012 270)
			(size 0.519938 1.4986)
			(layers "F.Cu" "F.Mask" "F.Paste")
			(net "M_C_CPU1_SA_DQS_DN<7>")
		)
		(pad "179" smd rect
			(at 2.050034 -34.425128 270)
			(size 0.519938 1.4986)
			(layers "F.Cu" "F.Mask" "F.Paste")
			(net "M_C_CPU1_SA_DQS_DP<7>")
		)
		(pad "180" smd rect
			(at 2.050034 -33.57499 270)
			(size 0.519938 1.4986)
			(layers "F.Cu" "F.Mask" "F.Paste")
			(net "GND")
		)
		(pad "181" smd rect
			(at 2.050034 -32.725106 270)
			(size 0.519938 1.4986)
			(layers "F.Cu" "F.Mask" "F.Paste")
			(net "M_C_CPU1_SA_DQ<22>")
		)
		(pad "182" smd rect
			(at 2.050034 -31.874968 270)
			(size 0.519938 1.4986)
			(layers "F.Cu" "F.Mask" "F.Paste")
			(net "GND")
		)
		(pad "183" smd rect
			(at 2.050034 -31.025084 270)
			(size 0.519938 1.4986)
			(layers "F.Cu" "F.Mask" "F.Paste")
			(net "M_C_CPU1_SA_DQ<23>")
		)
		(pad "184" smd rect
			(at 2.050034 -30.174946 270)
			(size 0.519938 1.4986)
			(layers "F.Cu" "F.Mask" "F.Paste")
			(net "GND")
		)
		(pad "185" smd rect
			(at 2.050034 -29.325062 270)
			(size 0.519938 1.4986)
			(layers "F.Cu" "F.Mask" "F.Paste")
			(net "M_C_CPU1_SA_DQ<26>")
		)
		(pad "186" smd rect
			(at 2.050034 -28.474924 270)
			(size 0.519938 1.4986)
			(layers "F.Cu" "F.Mask" "F.Paste")
			(net "GND")
		)
		(pad "187" smd rect
			(at 2.050034 -27.62504 270)
			(size 0.519938 1.4986)
			(layers "F.Cu" "F.Mask" "F.Paste")
			(net "M_C_CPU1_SA_DQ<27>")
		)
		(pad "188" smd rect
			(at 2.050034 -26.774902 270)
			(size 0.519938 1.4986)
			(layers "F.Cu" "F.Mask" "F.Paste")
			(net "GND")
		)
		(pad "189" smd rect
			(at 2.050034 -25.925018 270)
			(size 0.519938 1.4986)
			(layers "F.Cu" "F.Mask" "F.Paste")
			(net "M_C_CPU1_SA_DQS_DN<8>")
		)
		(pad "190" smd rect
			(at 2.050034 -25.07488 270)
			(size 0.519938 1.4986)
			(layers "F.Cu" "F.Mask" "F.Paste")
			(net "M_C_CPU1_SA_DQS_DP<8>")
		)
		(pad "191" smd rect
			(at 2.050034 -24.224996 270)
			(size 0.519938 1.4986)
			(layers "F.Cu" "F.Mask" "F.Paste")
			(net "GND")
		)
		(pad "192" smd rect
			(at 2.050034 -23.375112 270)
			(size 0.519938 1.4986)
			(layers "F.Cu" "F.Mask" "F.Paste")
			(net "M_C_CPU1_SA_DQ<30>")
		)
		(pad "193" smd rect
			(at 2.050034 -22.524974 270)
			(size 0.519938 1.4986)
			(layers "F.Cu" "F.Mask" "F.Paste")
			(net "GND")
		)
		(pad "194" smd rect
			(at 2.050034 -21.67509 270)
			(size 0.519938 1.4986)
			(layers "F.Cu" "F.Mask" "F.Paste")
			(net "M_C_CPU1_SA_DQ<31>")
		)
		(pad "195" smd rect
			(at 2.050034 -20.824952 270)
			(size 0.519938 1.4986)
			(layers "F.Cu" "F.Mask" "F.Paste")
			(net "GND")
		)
		(pad "196" smd rect
			(at 2.050034 -19.975068 270)
			(size 0.519938 1.4986)
			(layers "F.Cu" "F.Mask" "F.Paste")
			(net "M_C_CPU1_SA_CB<2>")
		)
		(pad "197" smd rect
			(at 2.050034 -19.12493 270)
			(size 0.519938 1.4986)
			(layers "F.Cu" "F.Mask" "F.Paste")
			(net "GND")
		)
		(pad "198" smd rect
			(at 2.050034 -18.275046 270)
			(size 0.519938 1.4986)
			(layers "F.Cu" "F.Mask" "F.Paste")
			(net "M_C_CPU1_SA_CB<3>")
		)
		(pad "199" smd rect
			(at 2.050034 -17.424908 270)
			(size 0.519938 1.4986)
			(layers "F.Cu" "F.Mask" "F.Paste")
			(net "GND")
		)
		(pad "200" smd rect
			(at 2.050034 -16.575024 270)
			(size 0.519938 1.4986)
			(layers "F.Cu" "F.Mask" "F.Paste")
			(net "M_C_CPU1_SA_DQS_DN<9>")
		)
		(pad "201" smd rect
			(at 2.050034 -15.724886 270)
			(size 0.519938 1.4986)
			(layers "F.Cu" "F.Mask" "F.Paste")
			(net "M_C_CPU1_SA_DQS_DP<9>")
		)
		(pad "202" smd rect
			(at 2.050034 -14.875002 270)
			(size 0.519938 1.4986)
			(layers "F.Cu" "F.Mask" "F.Paste")
			(net "GND")
		)
		(pad "203" smd rect
			(at 2.050034 -14.025118 270)
			(size 0.519938 1.4986)
			(layers "F.Cu" "F.Mask" "F.Paste")
			(net "M_C_CPU1_SA_CB<6>")
		)
		(pad "204" smd rect
			(at 2.050034 -13.17498 270)
			(size 0.519938 1.4986)
			(layers "F.Cu" "F.Mask" "F.Paste")
			(net "GND")
		)
		(pad "205" smd rect
			(at 2.050034 -12.325096 270)
			(size 0.519938 1.4986)
			(layers "F.Cu" "F.Mask" "F.Paste")
			(net "M_C_CPU1_SA_CB<7>")
		)
		(pad "206" smd rect
			(at 2.050034 -11.474958 270)
			(size 0.519938 1.4986)
			(layers "F.Cu" "F.Mask" "F.Paste")
			(net "GND")
		)
		(pad "207" smd rect
			(at 2.050034 -10.625074 270)
			(size 0.519938 1.4986)
			(layers "F.Cu" "F.Mask" "F.Paste")
			(net "RST_M_CD_CPU1_FPGA_N")
		)
		(pad "208" smd rect
			(at 2.050034 -9.774936 270)
			(size 0.519938 1.4986)
			(layers "F.Cu" "F.Mask" "F.Paste")
			(net "GND")
		)
		(pad "209" smd rect
			(at 2.050034 -8.925052 270)
			(size 0.519938 1.4986)
			(layers "F.Cu" "F.Mask" "F.Paste")
			(net "M_C_CPU1_SA_CS_N<1>")
		)
		(pad "210" smd rect
			(at 2.050034 -8.074914 270)
			(size 0.519938 1.4986)
			(layers "F.Cu" "F.Mask" "F.Paste")
			(net "GND")
		)
		(pad "211" smd rect
			(at 2.050034 -7.22503 270)
			(size 0.519938 1.4986)
			(layers "F.Cu" "F.Mask" "F.Paste")
			(net "M_C_CPU1_SA_CA<1>")
		)
		(pad "212" smd rect
			(at 2.050034 -6.374892 270)
			(size 0.519938 1.4986)
			(layers "F.Cu" "F.Mask" "F.Paste")
			(net "GND")
		)
		(pad "213" smd rect
			(at 2.050034 -5.525008 270)
			(size 0.519938 1.4986)
			(layers "F.Cu" "F.Mask" "F.Paste")
			(net "M_C_CPU1_SA_CA<3>")
		)
		(pad "214" smd rect
			(at 2.050034 -4.675124 270)
			(size 0.519938 1.4986)
			(layers "F.Cu" "F.Mask" "F.Paste")
			(net "GND")
		)
		(pad "215" smd rect
			(at 2.050034 -3.824986 270)
			(size 0.519938 1.4986)
			(layers "F.Cu" "F.Mask" "F.Paste")
			(net "M_C_CPU1_SA_CA<5>")
		)
		(pad "216" smd rect
			(at 2.050034 -2.975102 270)
			(size 0.519938 1.4986)
			(layers "F.Cu" "F.Mask" "F.Paste")
			(net "GND")
		)
		(pad "217" smd rect
			(at 2.050034 -2.124964 270)
			(size 0.519938 1.4986)
			(layers "F.Cu" "F.Mask" "F.Paste")
			(net "M_C_CPU1_CLK_DP<0>")
		)
		(pad "218" smd rect
			(at 2.050034 -1.27508 270)
			(size 0.519938 1.4986)
			(layers "F.Cu" "F.Mask" "F.Paste")
			(net "M_C_CPU1_CLK_DN<0>")
		)
		(pad "219" smd rect
			(at 2.050034 -0.424942 270)
			(size 0.519938 1.4986)
			(layers "F.Cu" "F.Mask" "F.Paste")
			(net "GND")
		)
		(pad "220" smd rect
			(at 2.050034 5.525008 270)
			(size 0.519938 1.4986)
			(layers "F.Cu" "F.Mask" "F.Paste")
			(net "TP_CHC_CPU1_DIMM1_FRU_4")
		)
		(pad "221" smd rect
			(at 2.050034 6.374892 270)
			(size 0.519938 1.4986)
			(layers "F.Cu" "F.Mask" "F.Paste")
			(net "M_C_CPU1_SB_CA<1>")
		)
		(pad "222" smd rect
			(at 2.050034 7.22503 270)
			(size 0.519938 1.4986)
			(layers "F.Cu" "F.Mask" "F.Paste")
			(net "GND")
		)
		(pad "223" smd rect
			(at 2.050034 8.074914 270)
			(size 0.519938 1.4986)
			(layers "F.Cu" "F.Mask" "F.Paste")
			(net "M_C_CPU1_SB_CA<3>")
		)
		(pad "224" smd rect
			(at 2.050034 8.925052 270)
			(size 0.519938 1.4986)
			(layers "F.Cu" "F.Mask" "F.Paste")
			(net "GND")
		)
	)
)
